# T6G (Grand Teton) — schematic netlist excerpt (pin names and nets, part order shuffled) for the footprints in the layout excerpt that follows; sources: Cadence DE-HDL packaged netlist, KiCad conversion of 04192023_DAF0TMB3IC0_F0TG_MB_C_brd_V02_OCP.brd

R442  Q_RES  1K 1% CHIP  pkg 0402LF  page 28 : A = RST_CPU0_RESETL_N ; B = PVDD18_S5_P0
C677  Q_CAP  1UF 4V 20% X6S  pkg 0201  page 301 : A = P1V8_CPU0_RT2_1A ; B = GND
PR370  Q_RES  2.2 1% CHIP  pkg 0402LF  page 223 : A = PVDDCR_CPU1_P1_PVCC ; B = PVDDIO_P1_VCC4

(kicad_pcb
	(version 20260206)
	(generator "pcbnew")
	(generator_version "10.0")
	(general
		(thickness 1.6)
		(legacy_teardrops no)
	)
	(paper "A4")
	(title_block
		(title "04192023_DAF0TMB3IC0_F0TG_MB_C_brd_V02_OCP.brd")
		(comment 1 "Grand Teton / footprints 5403-5405 of 8354")
	)
	(layers
		(0 "F.Cu" signal "TOP")
		(4 "In1.Cu" signal "GND")
		(6 "In2.Cu" signal "IN1")
		(8 "In3.Cu" signal "GND1")
		(10 "In4.Cu" signal "IN2")
		(12 "In5.Cu" signal "GND2")
		(14 "In6.Cu" signal "IN3")
		(16 "In7.Cu" signal "GND3")
		(18 "In8.Cu" signal "VCC")
		(20 "In9.Cu" signal "VCC1")
		(22 "In10.Cu" signal "GND4")
		(24 "In11.Cu" signal "IN4")
		(26 "In12.Cu" signal "GND5")
		(28 "In13.Cu" signal "IN5")
		(30 "In14.Cu" signal "GND6")
		(32 "In15.Cu" signal "IN6")
		(34 "In16.Cu" signal "GND7")
		(2 "B.Cu" signal "BOTTOM")
		(9 "F.Adhes" user "F.Adhesive")
		(11 "B.Adhes" user "B.Adhesive")
		(13 "F.Paste" user "Package Geometry/Pastemask Top")
		(15 "B.Paste" user "Package Geometry/Pastemask Bottom")
		(5 "F.SilkS" user "Ref Des/Silkscreen Top")
		(7 "B.SilkS" user "Ref Des/Silkscreen Bottom")
		(1 "F.Mask" user "Board Geometry/Soldermask Top")
		(3 "B.Mask" user "Board Geometry/Soldermask Bottom")
		(17 "Dwgs.User" user "User.Drawings")
		(19 "Cmts.User" user "User.Comments")
		(21 "Eco1.User" user "User.Eco1")
		(23 "Eco2.User" user "User.Eco2")
		(25 "Edge.Cuts" user "Board Geometry/Outline")
		(27 "Margin" user)
		(31 "F.CrtYd" user "Package Geometry/Place Bound Top")
		(29 "B.CrtYd" user "Package Geometry/Place Bound Bottom")
		(35 "F.Fab" user "Ref Des/Assembly Top")
		(33 "B.Fab" user "Ref Des/Assembly Bottom")
	)
	(footprint ""
		(layer "B.Cu")
		(at 410.346144 -396.393162 -90)
		(property "Reference" "C677"
			(at 0 0 90)
			(layer "B.SilkS")
			(hide yes)
			(effects
				(font
					(size 1.27 1.27)
				)
				(justify mirror)
			)
		)
		(property "Value" ""
			(at 0 0 90)
			(layer "B.Fab")
			(effects
				(font
					(size 1.27 1.27)
				)
				(justify mirror)
			)
		)
		(duplicate_pad_numbers_are_jumpers no)
		(fp_line
			(start -0.299974 0.150114)
			(end 0.299974 0.150114)
			(stroke
				(width 0.1)
				(type default)
			)
			(layer "B.Fab")
		)
		(fp_line
			(start 0.299974 0.150114)
			(end 0.299974 -0.150114)
			(stroke
				(width 0.1)
				(type default)
			)
			(layer "B.Fab")
		)
		(fp_line
			(start -0.299974 -0.150114)
			(end -0.299974 0.150114)
			(stroke
				(width 0.1)
				(type default)
			)
			(layer "B.Fab")
		)
		(fp_line
			(start 0.299974 -0.150114)
			(end -0.299974 -0.150114)
			(stroke
				(width 0.1)
				(type default)
			)
			(layer "B.Fab")
		)
		(pad "1" smd rect
			(at 0.2667 0 90)
			(size 0.3048 0.381)
			(layers "B.Cu" "B.Mask" "B.Paste")
			(net "P1V8_CPU0_RT2_1A")
		)
		(pad "2" smd rect
			(at -0.2667 0 90)
			(size 0.3048 0.381)
			(layers "B.Cu" "B.Mask" "B.Paste")
			(net "GND")
		)
	)
	(footprint ""
		(layer "B.Cu")
		(at 322.370958 -203.917296 90)
		(property "Reference" "R442"
			(at 0 0 90)
			(layer "B.SilkS")
			(hide yes)
			(effects
				(font
					(size 1.27 1.27)
				)
				(justify mirror)
			)
		)
		(property "Value" ""
			(at 0 0 90)
			(layer "B.Fab")
			(effects
				(font
					(size 1.27 1.27)
				)
				(justify mirror)
			)
		)
		(duplicate_pad_numbers_are_jumpers no)
		(fp_line
			(start 0.7874 -0.4064)
			(end -0.7874 -0.4064)
			(stroke
				(width 0.1524)
				(type default)
			)
			(layer "B.SilkS")
		)
		(fp_line
			(start -0.7874 -0.4064)
			(end -0.7874 0.4064)
			(stroke
				(width 0.1524)
				(type default)
			)
			(layer "B.SilkS")
		)
		(fp_line
			(start 0.7874 0.4064)
			(end 0.7874 -0.4064)
			(stroke
				(width 0.1524)
				(type default)
			)
			(layer "B.SilkS")
		)
		(fp_line
			(start -0.7874 0.4064)
			(end 0.7874 0.4064)
			(stroke
				(width 0.1524)
				(type default)
			)
			(layer "B.SilkS")
		)
		(fp_line
			(start 0.67945 -0.305054)
			(end 0.12065 -0.305054)
			(stroke
				(width 0.1)
				(type default)
			)
			(layer "B.Fab")
		)
		(fp_line
			(start 0.12065 -0.305054)
			(end 0.12065 -0.2794)
			(stroke
				(width 0.1)
				(type default)
			)
			(layer "B.Fab")
		)
		(fp_line
			(start -0.12065 -0.3048)
			(end -0.67945 -0.3048)
			(stroke
				(width 0.1)
				(type default)
			)
			(layer "B.Fab")
		)
		(fp_line
			(start -0.67945 -0.3048)
			(end -0.67945 0.3048)
			(stroke
				(width 0.1)
				(type default)
			)
			(layer "B.Fab")
		)
		(fp_line
			(start 0.12065 -0.2794)
			(end -0.12065 -0.2794)
			(stroke
				(width 0.1)
				(type default)
			)
			(layer "B.Fab")
		)
		(fp_line
			(start -0.12065 -0.2794)
			(end -0.12065 -0.3048)
			(stroke
				(width 0.1)
				(type default)
			)
			(layer "B.Fab")
		)
		(fp_line
			(start 0.12065 0.2794)
			(end 0.12065 0.3048)
			(stroke
				(width 0.1)
				(type default)
			)
			(layer "B.Fab")
		)
		(fp_line
			(start -0.120396 0.2794)
			(end 0.12065 0.2794)
			(stroke
				(width 0.1)
				(type default)
			)
			(layer "B.Fab")
		)
		(fp_line
			(start 0.67945 0.3048)
			(end 0.67945 -0.305054)
			(stroke
				(width 0.1)
				(type default)
			)
			(layer "B.Fab")
		)
		(fp_line
			(start 0.12065 0.3048)
			(end 0.67945 0.3048)
			(stroke
				(width 0.1)
				(type default)
			)
			(layer "B.Fab")
		)
		(fp_line
			(start -0.120396 0.3048)
			(end -0.120396 0.2794)
			(stroke
				(width 0.1)
				(type default)
			)
			(layer "B.Fab")
		)
		(fp_line
			(start -0.67945 0.3048)
			(end -0.120396 0.3048)
			(stroke
				(width 0.1)
				(type default)
			)
			(layer "B.Fab")
		)
		(pad "1" smd circle
			(at 0.40005 0 270)
			(size 0 0)
			(layers "B.Cu" "B.Mask" "B.Paste")
			(net "RST_CPU0_RESETL_N")
		)
		(pad "2" smd circle
			(at -0.40005 0 270)
			(size 0 0)
			(layers "B.Cu" "B.Mask" "B.Paste")
			(net "PVDD18_S5_P0")
		)
	)
	(footprint ""
		(layer "B.Cu")
		(at 26.289762 -347.780356 -90)
		(property "Reference" "PR370"
			(at 0 0 90)
			(layer "B.SilkS")
			(hide yes)
			(effects
				(font
					(size 1.27 1.27)
				)
				(justify mirror)
			)
		)
		(property "Value" ""
			(at 0 0 90)
			(layer "B.Fab")
			(effects
				(font
					(size 1.27 1.27)
				)
				(justify mirror)
			)
		)
		(duplicate_pad_numbers_are_jumpers no)
		(fp_line
			(start -0.7874 0.4064)
			(end 0.7874 0.4064)
			(stroke
				(width 0.1524)
				(type default)
			)
			(layer "B.SilkS")
		)
		(fp_line
			(start 0.7874 0.4064)
			(end 0.7874 -0.4064)
			(stroke
				(width 0.1524)
				(type default)
			)
			(layer "B.SilkS")
		)
		(fp_line
			(start -0.7874 -0.4064)
			(end -0.7874 0.4064)
			(stroke
				(width 0.1524)
				(type default)
			)
			(layer "B.SilkS")
		)
		(fp_line
			(start 0.7874 -0.4064)
			(end -0.7874 -0.4064)
			(stroke
				(width 0.1524)
				(type default)
			)
			(layer "B.SilkS")
		)
		(fp_line
			(start -0.67945 0.3048)
			(end -0.120396 0.3048)
			(stroke
				(width 0.1)
				(type default)
			)
			(layer "B.Fab")
		)
		(fp_line
			(start -0.120396 0.3048)
			(end -0.120396 0.2794)
			(stroke
				(width 0.1)
				(type default)
			)
			(layer "B.Fab")
		)
		(fp_line
			(start 0.12065 0.3048)
			(end 0.67945 0.3048)
			(stroke
				(width 0.1)
				(type default)
			)
			(layer "B.Fab")
		)
		(fp_line
			(start 0.67945 0.3048)
			(end 0.67945 -0.305054)
			(stroke
				(width 0.1)
				(type default)
			)
			(layer "B.Fab")
		)
		(fp_line
			(start -0.120396 0.2794)
			(end 0.12065 0.2794)
			(stroke
				(width 0.1)
				(type default)
			)
			(layer "B.Fab")
		)
		(fp_line
			(start 0.12065 0.2794)
			(end 0.12065 0.3048)
			(stroke
				(width 0.1)
				(type default)
			)
			(layer "B.Fab")
		)
		(fp_line
			(start -0.12065 -0.2794)
			(end -0.12065 -0.3048)
			(stroke
				(width 0.1)
				(type default)
			)
			(layer "B.Fab")
		)
		(fp_line
			(start 0.12065 -0.2794)
			(end -0.12065 -0.2794)
			(stroke
				(width 0.1)
				(type default)
			)
			(layer "B.Fab")
		)
		(fp_line
			(start -0.67945 -0.3048)
			(end -0.67945 0.3048)
			(stroke
				(width 0.1)
				(type default)
			)
			(layer "B.Fab")
		)
		(fp_line
			(start -0.12065 -0.3048)
			(end -0.67945 -0.3048)
			(stroke
				(width 0.1)
				(type default)
			)
			(layer "B.Fab")
		)
		(fp_line
			(start 0.12065 -0.305054)
			(end 0.12065 -0.2794)
			(stroke
				(width 0.1)
				(type default)
			)
			(layer "B.Fab")
		)
		(fp_line
			(start 0.67945 -0.305054)
			(end 0.12065 -0.305054)
			(stroke
				(width 0.1)
				(type default)
			)
			(layer "B.Fab")
		)
		(pad "1" smd circle
			(at 0.40005 0 90)
			(size 0 0)
			(layers "B.Cu" "B.Mask" "B.Paste")
			(net "PVDDCR_CPU1_P1_PVCC")
		)
		(pad "2" smd circle
			(at -0.40005 0 90)
			(size 0 0)
			(layers "B.Cu" "B.Mask" "B.Paste")
			(net "PVDDIO_P1_VCC4")
		)
	)
)
